(kicad_pcb
	(version 20260206)
	(generator "pcbnew")
	(generator_version "10.0")
	(general
		(thickness 1.6)
		(legacy_teardrops no)
	)
	(paper "A4")
	(title_block
		(title "01162023_DA0F0TEBIF0_F0T_Expander_BD_F_brd_V02_OCP.brd")
		(comment 1 "Grand Teton / footprints 4070-4075 of 9728")
	)
	(layers
		(0 "F.Cu" signal "TOP")
		(4 "In1.Cu" signal "GND")
		(6 "In2.Cu" signal "VCC")
		(8 "In3.Cu" signal "VCC1")
		(10 "In4.Cu" signal "GND1")
		(12 "In5.Cu" signal "IN1")
		(14 "In6.Cu" signal "GND2")
		(16 "In7.Cu" signal "IN2")
		(18 "In8.Cu" signal "GND3")
		(20 "In9.Cu" signal "IN3")
		(22 "In10.Cu" signal "GND4")
		(24 "In11.Cu" signal "IN4")
		(26 "In12.Cu" signal "GND5")
		(28 "In13.Cu" signal "IN5")
		(30 "In14.Cu" signal "GND6")
		(32 "In15.Cu" signal "IN6")
		(34 "In16.Cu" signal "GND7")
		(2 "B.Cu" signal "BOTTOM")
		(9 "F.Adhes" user "F.Adhesive")
		(11 "B.Adhes" user "B.Adhesive")
		(13 "F.Paste" user "Package Geometry/Pastemask Top")
		(15 "B.Paste" user "Package Geometry/Pastemask Bottom")
		(5 "F.SilkS" user "Ref Des/Silkscreen Top")
		(7 "B.SilkS" user "Ref Des/Silkscreen Bottom")
		(1 "F.Mask" user "Board Geometry/Soldermask Top")
		(3 "B.Mask" user "Board Geometry/Soldermask Bottom")
		(17 "Dwgs.User" user "User.Drawings")
		(19 "Cmts.User" user "User.Comments")
		(21 "Eco1.User" user "User.Eco1")
		(23 "Eco2.User" user "User.Eco2")
		(25 "Edge.Cuts" user "Board Geometry/Outline")
		(27 "Margin" user)
		(31 "F.CrtYd" user "Package Geometry/Place Bound Top")
		(29 "B.CrtYd" user "Package Geometry/Place Bound Bottom")
		(35 "F.Fab" user "Ref Des/Assembly Top")
		(33 "B.Fab" user "Ref Des/Assembly Bottom")
	)
	(footprint ""
		(layer "F.Cu")
		(at 237.59414 -29.507688 -90)
		(property "Reference" "PC941"
			(at 0 0 270)
			(layer "F.SilkS")
			(hide yes)
			(effects
				(font
					(size 1.27 1.27)
				)
			)
		)
		(property "Value" ""
			(at 0 0 270)
			(layer "F.Fab")
			(effects
				(font
					(size 1.27 1.27)
				)
			)
		)
		(duplicate_pad_numbers_are_jumpers no)
		(fp_line
			(start -1.524 0.762)
			(end -1.524 -0.762)
			(stroke
				(width 0.1524)
				(type default)
			)
			(layer "F.SilkS")
		)
		(fp_line
			(start 1.524 0.762)
			(end -1.524 0.762)
			(stroke
				(width 0.1524)
				(type default)
			)
			(layer "F.SilkS")
		)
		(fp_line
			(start -1.524 -0.762)
			(end 1.524 -0.762)
			(stroke
				(width 0.1524)
				(type default)
			)
			(layer "F.SilkS")
		)
		(fp_line
			(start 1.524 -0.762)
			(end 1.524 0.762)
			(stroke
				(width 0.1524)
				(type default)
			)
			(layer "F.SilkS")
		)
		(fp_line
			(start -1.1049 0.724916)
			(end 1.1049 0.724916)
			(stroke
				(width 0.1)
				(type default)
			)
			(layer "F.Fab")
		)
		(fp_line
			(start 1.1049 0.724916)
			(end 1.1049 -0.724916)
			(stroke
				(width 0.1)
				(type default)
			)
			(layer "F.Fab")
		)
		(fp_line
			(start -1.1049 -0.724916)
			(end -1.1049 0.724916)
			(stroke
				(width 0.1)
				(type default)
			)
			(layer "F.Fab")
		)
		(fp_line
			(start 1.1049 -0.724916)
			(end -1.1049 -0.724916)
			(stroke
				(width 0.1)
				(type default)
			)
			(layer "F.Fab")
		)
		(pad "1" smd rect
			(at -0.889 0 90)
			(size 1.016 1.27)
			(layers "F.Cu" "F.Mask" "F.Paste")
			(net "P3V3_SSD8")
		)
		(pad "2" smd rect
			(at 0.889 0 90)
			(size 1.016 1.27)
			(layers "F.Cu" "F.Mask" "F.Paste")
			(net "GND")
		)
	)
	(footprint ""
		(layer "F.Cu")
		(at 154.707844 -157.3784 180)
		(property "Reference" "R114"
			(at 0 0 180)
			(layer "F.SilkS")
			(hide yes)
			(effects
				(font
					(size 1.27 1.27)
				)
			)
		)
		(property "Value" ""
			(at 0 0 180)
			(layer "F.Fab")
			(effects
				(font
					(size 1.27 1.27)
				)
			)
		)
		(duplicate_pad_numbers_are_jumpers no)
		(fp_line
			(start 0.7874 0.4064)
			(end -0.7874 0.4064)
			(stroke
				(width 0.1524)
				(type default)
			)
			(layer "F.SilkS")
		)
		(fp_line
			(start 0.7874 -0.4064)
			(end 0.7874 0.4064)
			(stroke
				(width 0.1524)
				(type default)
			)
			(layer "F.SilkS")
		)
		(fp_line
			(start -0.7874 0.4064)
			(end -0.7874 -0.4064)
			(stroke
				(width 0.1524)
				(type default)
			)
			(layer "F.SilkS")
		)
		(fp_line
			(start -0.7874 -0.4064)
			(end 0.7874 -0.4064)
			(stroke
				(width 0.1524)
				(type default)
			)
			(layer "F.SilkS")
		)
		(fp_line
			(start 0.67945 0.3048)
			(end 0.120396 0.3048)
			(stroke
				(width 0.1)
				(type default)
			)
			(layer "F.Fab")
		)
		(fp_line
			(start 0.67945 -0.3048)
			(end 0.67945 0.3048)
			(stroke
				(width 0.1)
				(type default)
			)
			(layer "F.Fab")
		)
		(fp_line
			(start 0.12065 -0.2794)
			(end 0.12065 -0.3048)
			(stroke
				(width 0.1)
				(type default)
			)
			(layer "F.Fab")
		)
		(fp_line
			(start 0.12065 -0.3048)
			(end 0.67945 -0.3048)
			(stroke
				(width 0.1)
				(type default)
			)
			(layer "F.Fab")
		)
		(fp_line
			(start 0.120396 0.3048)
			(end 0.120396 0.2794)
			(stroke
				(width 0.1)
				(type default)
			)
			(layer "F.Fab")
		)
		(fp_line
			(start 0.120396 0.2794)
			(end -0.12065 0.2794)
			(stroke
				(width 0.1)
				(type default)
			)
			(layer "F.Fab")
		)
		(fp_line
			(start -0.12065 0.3048)
			(end -0.67945 0.3048)
			(stroke
				(width 0.1)
				(type default)
			)
			(layer "F.Fab")
		)
		(fp_line
			(start -0.12065 0.2794)
			(end -0.12065 0.3048)
			(stroke
				(width 0.1)
				(type default)
			)
			(layer "F.Fab")
		)
		(fp_line
			(start -0.12065 -0.2794)
			(end 0.12065 -0.2794)
			(stroke
				(width 0.1)
				(type default)
			)
			(layer "F.Fab")
		)
		(fp_line
			(start -0.12065 -0.305054)
			(end -0.12065 -0.2794)
			(stroke
				(width 0.1)
				(type default)
			)
			(layer "F.Fab")
		)
		(fp_line
			(start -0.67945 0.3048)
			(end -0.67945 -0.305054)
			(stroke
				(width 0.1)
				(type default)
			)
			(layer "F.Fab")
		)
		(fp_line
			(start -0.67945 -0.305054)
			(end -0.12065 -0.305054)
			(stroke
				(width 0.1)
				(type default)
			)
			(layer "F.Fab")
		)
		(pad "1" smd circle
			(at -0.40005 0 180)
			(size 0 0)
			(layers "F.Cu" "F.Mask" "F.Paste")
			(net "NIC2_DATA_IN")
		)
		(pad "2" smd circle
			(at 0.40005 0 180)
			(size 0 0)
			(layers "F.Cu" "F.Mask" "F.Paste")
			(net "P3V3_NIC2")
		)
	)
	(footprint ""
		(layer "F.Cu")
		(at 226.455224 -35.876738)
		(property "Reference" "R6080"
			(at 0 0 0)
			(layer "F.SilkS")
			(hide yes)
			(effects
				(font
					(size 1.27 1.27)
				)
			)
		)
		(property "Value" ""
			(at 0 0 0)
			(layer "F.Fab")
			(effects
				(font
					(size 1.27 1.27)
				)
			)
		)
		(duplicate_pad_numbers_are_jumpers no)
		(fp_line
			(start -0.7874 -0.4064)
			(end 0.7874 -0.4064)
			(stroke
				(width 0.1524)
				(type default)
			)
			(layer "F.SilkS")
		)
		(fp_line
			(start -0.7874 0.4064)
			(end -0.7874 -0.4064)
			(stroke
				(width 0.1524)
				(type default)
			)
			(layer "F.SilkS")
		)
		(fp_line
			(start 0.7874 -0.4064)
			(end 0.7874 0.4064)
			(stroke
				(width 0.1524)
				(type default)
			)
			(layer "F.SilkS")
		)
		(fp_line
			(start 0.7874 0.4064)
			(end -0.7874 0.4064)
			(stroke
				(width 0.1524)
				(type default)
			)
			(layer "F.SilkS")
		)
		(fp_line
			(start -0.67945 -0.305054)
			(end -0.12065 -0.305054)
			(stroke
				(width 0.1)
				(type default)
			)
			(layer "F.Fab")
		)
		(fp_line
			(start -0.67945 0.3048)
			(end -0.67945 -0.305054)
			(stroke
				(width 0.1)
				(type default)
			)
			(layer "F.Fab")
		)
		(fp_line
			(start -0.12065 -0.305054)
			(end -0.12065 -0.2794)
			(stroke
				(width 0.1)
				(type default)
			)
			(layer "F.Fab")
		)
		(fp_line
			(start -0.12065 -0.2794)
			(end 0.12065 -0.2794)
			(stroke
				(width 0.1)
				(type default)
			)
			(layer "F.Fab")
		)
		(fp_line
			(start -0.12065 0.2794)
			(end -0.12065 0.3048)
			(stroke
				(width 0.1)
				(type default)
			)
			(layer "F.Fab")
		)
		(fp_line
			(start -0.12065 0.3048)
			(end -0.67945 0.3048)
			(stroke
				(width 0.1)
				(type default)
			)
			(layer "F.Fab")
		)
		(fp_line
			(start 0.120396 0.2794)
			(end -0.12065 0.2794)
			(stroke
				(width 0.1)
				(type default)
			)
			(layer "F.Fab")
		)
		(fp_line
			(start 0.120396 0.3048)
			(end 0.120396 0.2794)
			(stroke
				(width 0.1)
				(type default)
			)
			(layer "F.Fab")
		)
		(fp_line
			(start 0.12065 -0.3048)
			(end 0.67945 -0.3048)
			(stroke
				(width 0.1)
				(type default)
			)
			(layer "F.Fab")
		)
		(fp_line
			(start 0.12065 -0.2794)
			(end 0.12065 -0.3048)
			(stroke
				(width 0.1)
				(type default)
			)
			(layer "F.Fab")
		)
		(fp_line
			(start 0.67945 -0.3048)
			(end 0.67945 0.3048)
			(stroke
				(width 0.1)
				(type default)
			)
			(layer "F.Fab")
		)
		(fp_line
			(start 0.67945 0.3048)
			(end 0.120396 0.3048)
			(stroke
				(width 0.1)
				(type default)
			)
			(layer "F.Fab")
		)
		(pad "1" smd circle
			(at -0.40005 0)
			(size 0 0)
			(layers "F.Cu" "F.Mask" "F.Paste")
			(net "P3V3_AUX")
		)
		(pad "2" smd circle
			(at 0.40005 0)
			(size 0 0)
			(layers "F.Cu" "F.Mask" "F.Paste")
			(net "PWRGD_P3V3_SSD8_D")
		)
	)
	(footprint ""
		(layer "F.Cu")
		(at 234.65536 -368.182144)
		(property "Reference" "PR38"
			(at 0 0 0)
			(layer "F.SilkS")
			(hide yes)
			(effects
				(font
					(size 1.27 1.27)
				)
			)
		)
		(property "Value" ""
			(at 0 0 0)
			(layer "F.Fab")
			(effects
				(font
					(size 1.27 1.27)
				)
			)
		)
		(duplicate_pad_numbers_are_jumpers no)
		(fp_line
			(start -0.7874 -0.4064)
			(end 0.7874 -0.4064)
			(stroke
				(width 0.1524)
				(type default)
			)
			(layer "F.SilkS")
		)
		(fp_line
			(start -0.7874 0.4064)
			(end -0.7874 -0.4064)
			(stroke
				(width 0.1524)
				(type default)
			)
			(layer "F.SilkS")
		)
		(fp_line
			(start 0.7874 -0.4064)
			(end 0.7874 0.4064)
			(stroke
				(width 0.1524)
				(type default)
			)
			(layer "F.SilkS")
		)
		(fp_line
			(start 0.7874 0.4064)
			(end -0.7874 0.4064)
			(stroke
				(width 0.1524)
				(type default)
			)
			(layer "F.SilkS")
		)
		(fp_line
			(start -0.67945 -0.305054)
			(end -0.12065 -0.305054)
			(stroke
				(width 0.1)
				(type default)
			)
			(layer "F.Fab")
		)
		(fp_line
			(start -0.67945 0.3048)
			(end -0.67945 -0.305054)
			(stroke
				(width 0.1)
				(type default)
			)
			(layer "F.Fab")
		)
		(fp_line
			(start -0.12065 -0.305054)
			(end -0.12065 -0.2794)
			(stroke
				(width 0.1)
				(type default)
			)
			(layer "F.Fab")
		)
		(fp_line
			(start -0.12065 -0.2794)
			(end 0.12065 -0.2794)
			(stroke
				(width 0.1)
				(type default)
			)
			(layer "F.Fab")
		)
		(fp_line
			(start -0.12065 0.2794)
			(end -0.12065 0.3048)
			(stroke
				(width 0.1)
				(type default)
			)
			(layer "F.Fab")
		)
		(fp_line
			(start -0.12065 0.3048)
			(end -0.67945 0.3048)
			(stroke
				(width 0.1)
				(type default)
			)
			(layer "F.Fab")
		)
		(fp_line
			(start 0.120396 0.2794)
			(end -0.12065 0.2794)
			(stroke
				(width 0.1)
				(type default)
			)
			(layer "F.Fab")
		)
		(fp_line
			(start 0.120396 0.3048)
			(end 0.120396 0.2794)
			(stroke
				(width 0.1)
				(type default)
			)
			(layer "F.Fab")
		)
		(fp_line
			(start 0.12065 -0.3048)
			(end 0.67945 -0.3048)
			(stroke
				(width 0.1)
				(type default)
			)
			(layer "F.Fab")
		)
		(fp_line
			(start 0.12065 -0.2794)
			(end 0.12065 -0.3048)
			(stroke
				(width 0.1)
				(type default)
			)
			(layer "F.Fab")
		)
		(fp_line
			(start 0.67945 -0.3048)
			(end 0.67945 0.3048)
			(stroke
				(width 0.1)
				(type default)
			)
			(layer "F.Fab")
		)
		(fp_line
			(start 0.67945 0.3048)
			(end 0.120396 0.3048)
			(stroke
				(width 0.1)
				(type default)
			)
			(layer "F.Fab")
		)
		(pad "1" smd circle
			(at -0.40005 0)
			(size 0 0)
			(layers "F.Cu" "F.Mask" "F.Paste")
			(net "HSC_D_OC_2")
		)
		(pad "2" smd circle
			(at 0.40005 0)
			(size 0 0)
			(layers "F.Cu" "F.Mask" "F.Paste")
			(net "HSC_D_OC")
		)
	)
	(footprint ""
		(layer "F.Cu")
		(at 209.24266 -70.844918 -90)
		(property "Reference" "PD35"
			(at 4.093718 2.12979 90)
			(unlocked yes)
			(layer "F.SilkS")
			(effects
				(font
					(size 0.7874 0.5842)
					(thickness 0.1524)
				)
				(justify left)
			)
		)
		(property "Value" ""
			(at 0 0 270)
			(layer "F.Fab")
			(effects
				(font
					(size 1.27 1.27)
				)
			)
		)
		(duplicate_pad_numbers_are_jumpers no)
		(fp_line
			(start -3.400044 1.459992)
			(end -3.400044 -1.459992)
			(stroke
				(width 0.1524)
				(type default)
			)
			(layer "F.SilkS")
		)
		(fp_line
			(start 4.107942 1.459992)
			(end -3.400044 1.459992)
			(stroke
				(width 0.1524)
				(type default)
			)
			(layer "F.SilkS")
		)
		(fp_line
			(start -3.400044 -1.459992)
			(end 4.107942 -1.459992)
			(stroke
				(width 0.1524)
				(type default)
			)
			(layer "F.SilkS")
		)
		(fp_line
			(start 4.107942 -1.459992)
			(end 4.107942 1.459992)
			(stroke
				(width 0.1524)
				(type default)
			)
			(layer "F.SilkS")
		)
		(fp_poly
			(pts
				(xy 4.107942 -1.459992) (xy 4.107942 1.459992) (xy 3.308096 1.459992) (xy 3.308096 -1.459992)
			)
			(stroke
				(width 0)
				(type default)
			)
			(fill yes)
			(layer "F.SilkS")
		)
		(fp_line
			(start -2.29997 1.459992)
			(end -2.29997 -1.459992)
			(stroke
				(width 0.1)
				(type default)
			)
			(layer "F.Fab")
		)
		(fp_line
			(start 2.29997 1.459992)
			(end -2.29997 1.459992)
			(stroke
				(width 0.1)
				(type default)
			)
			(layer "F.Fab")
		)
		(fp_line
			(start -2.29997 -1.459992)
			(end 2.29997 -1.459992)
			(stroke
				(width 0.1)
				(type default)
			)
			(layer "F.Fab")
		)
		(fp_line
			(start 2.29997 -1.459992)
			(end 2.29997 1.459992)
			(stroke
				(width 0.1)
				(type default)
			)
			(layer "F.Fab")
		)
		(fp_text user "-"
			(at 5.4102 0.29845 90)
			(unlocked yes)
			(layer "F.SilkS")
			(effects
				(font
					(size 1.905 1.4224)
					(thickness 0.1524)
				)
				(justify left)
			)
		)
		(fp_text user "+"
			(at -5.202682 -0.188722 270)
			(unlocked yes)
			(layer "F.SilkS")
			(effects
				(font
					(size 1.905 1.4224)
					(thickness 0.1524)
				)
				(justify left)
			)
		)
		(fp_text user "-"
			(at 5.4102 0.29845 90)
			(unlocked yes)
			(layer "F.Fab")
			(effects
				(font
					(size 1.905 1.4224)
					(thickness 0.1524)
				)
				(justify left)
			)
		)
		(fp_text user "+"
			(at -4.7752 -0.12065 270)
			(unlocked yes)
			(layer "F.Fab")
			(effects
				(font
					(size 1.905 1.4224)
					(thickness 0.1524)
				)
				(justify left)
			)
		)
		(pad "A" smd rect
			(at -1.999996 0)
			(size 1.7018 2.5146)
			(layers "F.Cu" "F.Mask" "F.Paste")
			(net "GND")
		)
		(pad "C" smd rect
			(at 1.999996 0)
			(size 1.7018 2.5146)
			(layers "F.Cu" "F.Mask" "F.Paste")
			(net "P12V_SSD7_R")
		)
	)
	(footprint ""
		(layer "F.Cu")
		(at 350.64192 -27.006296 -90)
		(property "Reference" "PR7124"
			(at 0 0 270)
			(layer "F.SilkS")
			(hide yes)
			(effects
				(font
					(size 1.27 1.27)
				)
			)
		)
		(property "Value" ""
			(at 0 0 270)
			(layer "F.Fab")
			(effects
				(font
					(size 1.27 1.27)
				)
			)
		)
		(duplicate_pad_numbers_are_jumpers no)
		(fp_line
			(start -0.7874 0.4064)
			(end -0.7874 -0.4064)
			(stroke
				(width 0.1524)
				(type default)
			)
			(layer "F.SilkS")
		)
		(fp_line
			(start 0.7874 0.4064)
			(end -0.7874 0.4064)
			(stroke
				(width 0.1524)
				(type default)
			)
			(layer "F.SilkS")
		)
		(fp_line
			(start -0.7874 -0.4064)
			(end 0.7874 -0.4064)
			(stroke
				(width 0.1524)
				(type default)
			)
			(layer "F.SilkS")
		)
		(fp_line
			(start 0.7874 -0.4064)
			(end 0.7874 0.4064)
			(stroke
				(width 0.1524)
				(type default)
			)
			(layer "F.SilkS")
		)
		(fp_line
			(start -0.67945 0.3048)
			(end -0.67945 -0.305054)
			(stroke
				(width 0.1)
				(type default)
			)
			(layer "F.Fab")
		)
		(fp_line
			(start -0.12065 0.3048)
			(end -0.67945 0.3048)
			(stroke
				(width 0.1)
				(type default)
			)
			(layer "F.Fab")
		)
		(fp_line
			(start 0.120396 0.3048)
			(end 0.120396 0.2794)
			(stroke
				(width 0.1)
				(type default)
			)
			(layer "F.Fab")
		)
		(fp_line
			(start 0.67945 0.3048)
			(end 0.120396 0.3048)
			(stroke
				(width 0.1)
				(type default)
			)
			(layer "F.Fab")
		)
		(fp_line
			(start -0.12065 0.2794)
			(end -0.12065 0.3048)
			(stroke
				(width 0.1)
				(type default)
			)
			(layer "F.Fab")
		)
		(fp_line
			(start 0.120396 0.2794)
			(end -0.12065 0.2794)
			(stroke
				(width 0.1)
				(type default)
			)
			(layer "F.Fab")
		)
		(fp_line
			(start -0.12065 -0.2794)
			(end 0.12065 -0.2794)
			(stroke
				(width 0.1)
				(type default)
			)
			(layer "F.Fab")
		)
		(fp_line
			(start 0.12065 -0.2794)
			(end 0.12065 -0.3048)
			(stroke
				(width 0.1)
				(type default)
			)
			(layer "F.Fab")
		)
		(fp_line
			(start 0.12065 -0.3048)
			(end 0.67945 -0.3048)
			(stroke
				(width 0.1)
				(type default)
			)
			(layer "F.Fab")
		)
		(fp_line
			(start 0.67945 -0.3048)
			(end 0.67945 0.3048)
			(stroke
				(width 0.1)
				(type default)
			)
			(layer "F.Fab")
		)
		(fp_line
			(start -0.67945 -0.305054)
			(end -0.12065 -0.305054)
			(stroke
				(width 0.1)
				(type default)
			)
			(layer "F.Fab")
		)
		(fp_line
			(start -0.12065 -0.305054)
			(end -0.12065 -0.2794)
			(stroke
				(width 0.1)
				(type default)
			)
			(layer "F.Fab")
		)
		(pad "1" smd circle
			(at -0.40005 0 270)
			(size 0 0)
			(layers "F.Cu" "F.Mask" "F.Paste")
			(net "P3V3_SSD12_CO_ILIMIT")
		)
		(pad "2" smd circle
			(at 0.40005 0 270)
			(size 0 0)
			(layers "F.Cu" "F.Mask" "F.Paste")
			(net "GND")
		)
	)
)
